# S9S_MB_2U (Grand Teton) — schematic netlist excerpt (pin names and nets, part order shuffled) for the footprints in the layout excerpt that follows; sources: Cadence DE-HDL packaged netlist, KiCad conversion of 03242023_DA0F0TMBIJ0_F0T_Motherboard_J_brd_V01_OCP.brd

U39  TCA9548APWR  IC  pkg TSSOP24XA  page 233
  A0  = PCA9548_PCIE0_ADDR0
  A1  = PCA9548_PCIE0_ADDR1
  \reset#\  = PU_RST_SMB_PCIE2_N
  SD0  = SMB_VR_3V3AUX_SDA_R6
  SC0  = SMB_VR_3V3AUX_SCL_R6
  SD1  = SMB_LM75_0_3V3AUX_SDA_R
  SC1  = SMB_LM75_0_3V3AUX_SCL_R
  SD2  = SMB_LM75_1_3V3AUX_SDA_R
  SC2  = SMB_LM75_1_3V3AUX_SCL_R
  SD3  = SMB_LM75_2_3V3AUX_SDA_R
  SC3  = SMB_LM75_2_3V3AUX_SCL_R
  GND  = GND
  SD4  = SMB_LM75_3_3V3AUX_SDA_R
  SC4  = SMB_LM75_3_3V3AUX_SCL_R
  SD5  = NC
  SC5  = NC
  SD6  = NC
  SC6  = NC
  SD7  = NC
  SC7  = NC
  A2  = PCA9548_PCIE0_ADDR2
  SCL  = SMB_VR_SENSOR_3V3AUX_SCL_R
  SDA  = SMB_VR_SENSOR_3V3AUX_SDA_R
  VCC  = P3V3_AUX

(kicad_pcb
	(version 20260206)
	(generator "pcbnew")
	(generator_version "10.0")
	(general
		(thickness 1.6)
		(legacy_teardrops no)
	)
	(paper "A4")
	(title_block
		(title "03242023_DA0F0TMBIJ0_F0T_Motherboard_J_brd_V01_OCP.brd")
		(comment 1 "Grand Teton / footprints 1294-1294 of 6105")
	)
	(layers
		(0 "F.Cu" signal "TOP")
		(4 "In1.Cu" signal "GND")
		(6 "In2.Cu" signal "IN1")
		(8 "In3.Cu" signal "GND1")
		(10 "In4.Cu" signal "IN2")
		(12 "In5.Cu" signal "GND2")
		(14 "In6.Cu" signal "IN3")
		(16 "In7.Cu" signal "GND3")
		(18 "In8.Cu" signal "VCC")
		(20 "In9.Cu" signal "VCC1")
		(22 "In10.Cu" signal "GND4")
		(24 "In11.Cu" signal "IN4")
		(26 "In12.Cu" signal "GND5")
		(28 "In13.Cu" signal "IN5")
		(30 "In14.Cu" signal "GND6")
		(32 "In15.Cu" signal "IN6")
		(34 "In16.Cu" signal "GND7")
		(2 "B.Cu" signal "BOTTOM")
		(9 "F.Adhes" user "F.Adhesive")
		(11 "B.Adhes" user "B.Adhesive")
		(13 "F.Paste" user "Package Geometry/Pastemask Top")
		(15 "B.Paste" user "Package Geometry/Pastemask Bottom")
		(5 "F.SilkS" user "Ref Des/Silkscreen Top")
		(7 "B.SilkS" user "Ref Des/Silkscreen Bottom")
		(1 "F.Mask" user "Board Geometry/Soldermask Top")
		(3 "B.Mask" user "Board Geometry/Soldermask Bottom")
		(17 "Dwgs.User" user "User.Drawings")
		(19 "Cmts.User" user "User.Comments")
		(21 "Eco1.User" user "User.Eco1")
		(23 "Eco2.User" user "User.Eco2")
		(25 "Edge.Cuts" user "Board Geometry/Outline")
		(27 "Margin" user)
		(31 "F.CrtYd" user "Package Geometry/Place Bound Top")
		(29 "B.CrtYd" user "Package Geometry/Place Bound Bottom")
		(35 "F.Fab" user "Ref Des/Assembly Top")
		(33 "B.Fab" user "Ref Des/Assembly Bottom")
	)
	(footprint ""
		(layer "F.Cu")
		(at 61.175646 -111.226346)
		(property "Reference" "U39"
			(at -2.1844 -4.587748 0)
			(unlocked yes)
			(layer "F.SilkS")
			(effects
				(font
					(size 0.7874 0.5842)
					(thickness 0.1524)
				)
				(justify left)
			)
		)
		(property "Value" ""
			(at 0 0 0)
			(layer "F.Fab")
			(effects
				(font
					(size 1.27 1.27)
				)
			)
		)
		(duplicate_pad_numbers_are_jumpers no)
		(fp_line
			(start -1.8542 -3.949954)
			(end -1.8542 3.949954)
			(stroke
				(width 0.1524)
				(type default)
			)
			(layer "F.SilkS")
		)
		(fp_line
			(start -1.8542 3.949954)
			(end 1.8542 3.949954)
			(stroke
				(width 0.1524)
				(type default)
			)
			(layer "F.SilkS")
		)
		(fp_line
			(start -1.282954 -3.949954)
			(end -1.8542 -3.949954)
			(stroke
				(width 0.1524)
				(type default)
			)
			(layer "F.SilkS")
		)
		(fp_line
			(start 0 -2.667)
			(end -1.282954 -3.949954)
			(stroke
				(width 0.1524)
				(type default)
			)
			(layer "F.SilkS")
		)
		(fp_line
			(start 1.282954 -3.949954)
			(end 0 -2.667)
			(stroke
				(width 0.1524)
				(type default)
			)
			(layer "F.SilkS")
		)
		(fp_line
			(start 1.8542 -3.949954)
			(end 1.282954 -3.949954)
			(stroke
				(width 0.1524)
				(type default)
			)
			(layer "F.SilkS")
		)
		(fp_line
			(start 1.8542 3.949954)
			(end 1.8542 -3.949954)
			(stroke
				(width 0.1524)
				(type default)
			)
			(layer "F.SilkS")
		)
		(fp_poly
			(pts
				(xy -4.8006 -4.08305) (xy -4.8006 -3.06705) (xy -3.7846 -3.57505)
			)
			(stroke
				(width 0)
				(type default)
			)
			(fill yes)
			(layer "F.SilkS")
		)
		(fp_line
			(start -2.249932 -3.949954)
			(end -2.249932 3.949954)
			(stroke
				(width 0.1)
				(type default)
			)
			(layer "F.Fab")
		)
		(fp_line
			(start -2.249932 3.949954)
			(end 2.249932 3.949954)
			(stroke
				(width 0.1)
				(type default)
			)
			(layer "F.Fab")
		)
		(fp_line
			(start 2.249932 -3.949954)
			(end -2.249932 -3.949954)
			(stroke
				(width 0.1)
				(type default)
			)
			(layer "F.Fab")
		)
		(fp_line
			(start 2.249932 3.949954)
			(end 2.249932 -3.949954)
			(stroke
				(width 0.1)
				(type default)
			)
			(layer "F.Fab")
		)
		(fp_poly
			(pts
				(xy -4.8006 -4.08305) (xy -4.8006 -3.06705) (xy -3.7846 -3.57505)
			)
			(stroke
				(width 0)
				(type default)
			)
			(fill yes)
			(layer "F.Fab")
		)
		(pad "1" smd rect
			(at -2.800096 -3.57505 270)
			(size 0.3048 1.6002)
			(layers "F.Cu" "F.Mask" "F.Paste")
			(net "PCA9548_PCIE0_ADDR0")
		)
		(pad "2" smd rect
			(at -2.800096 -2.925064 270)
			(size 0.3048 1.6002)
			(layers "F.Cu" "F.Mask" "F.Paste")
			(net "PCA9548_PCIE0_ADDR1")
		)
		(pad "3" smd rect
			(at -2.800096 -2.275078 270)
			(size 0.3048 1.6002)
			(layers "F.Cu" "F.Mask" "F.Paste")
			(net "PU_RST_SMB_PCIE2_N")
		)
		(pad "4" smd rect
			(at -2.800096 -1.625092 270)
			(size 0.3048 1.6002)
			(layers "F.Cu" "F.Mask" "F.Paste")
			(net "SMB_VR_3V3AUX_SDA_R6")
		)
		(pad "5" smd rect
			(at -2.800096 -0.975106 270)
			(size 0.3048 1.6002)
			(layers "F.Cu" "F.Mask" "F.Paste")
			(net "SMB_VR_3V3AUX_SCL_R6")
		)
		(pad "6" smd rect
			(at -2.800096 -0.32512 270)
			(size 0.3048 1.6002)
			(layers "F.Cu" "F.Mask" "F.Paste")
			(net "SMB_LM75_0_3V3AUX_SDA_R")
		)
		(pad "7" smd rect
			(at -2.800096 0.32512 270)
			(size 0.3048 1.6002)
			(layers "F.Cu" "F.Mask" "F.Paste")
			(net "SMB_LM75_0_3V3AUX_SCL_R")
		)
		(pad "8" smd rect
			(at -2.800096 0.975106 270)
			(size 0.3048 1.6002)
			(layers "F.Cu" "F.Mask" "F.Paste")
			(net "SMB_LM75_1_3V3AUX_SDA_R")
		)
		(pad "9" smd rect
			(at -2.800096 1.625092 270)
			(size 0.3048 1.6002)
			(layers "F.Cu" "F.Mask" "F.Paste")
			(net "SMB_LM75_1_3V3AUX_SCL_R")
		)
		(pad "10" smd rect
			(at -2.800096 2.275078 270)
			(size 0.3048 1.6002)
			(layers "F.Cu" "F.Mask" "F.Paste")
			(net "SMB_LM75_2_3V3AUX_SDA_R")
		)
		(pad "11" smd rect
			(at -2.800096 2.925064 270)
			(size 0.3048 1.6002)
			(layers "F.Cu" "F.Mask" "F.Paste")
			(net "SMB_LM75_2_3V3AUX_SCL_R")
		)
		(pad "12" smd rect
			(at -2.800096 3.57505 270)
			(size 0.3048 1.6002)
			(layers "F.Cu" "F.Mask" "F.Paste")
			(net "GND")
		)
		(pad "13" smd rect
			(at 2.800096 3.57505 270)
			(size 0.3048 1.6002)
			(layers "F.Cu" "F.Mask" "F.Paste")
			(net "SMB_LM75_3_3V3AUX_SDA_R")
		)
		(pad "14" smd rect
			(at 2.800096 2.925064 270)
			(size 0.3048 1.6002)
			(layers "F.Cu" "F.Mask" "F.Paste")
			(net "SMB_LM75_3_3V3AUX_SCL_R")
		)
		(pad "15" smd rect
			(at 2.800096 2.275078 270)
			(size 0.3048 1.6002)
			(layers "F.Cu" "F.Mask" "F.Paste")
			(net "Net_8618")
		)
		(pad "16" smd rect
			(at 2.800096 1.625092 270)
			(size 0.3048 1.6002)
			(layers "F.Cu" "F.Mask" "F.Paste")
			(net "Net_8621")
		)
		(pad "17" smd rect
			(at 2.800096 0.975106 270)
			(size 0.3048 1.6002)
			(layers "F.Cu" "F.Mask" "F.Paste")
			(net "Net_8617")
		)
		(pad "18" smd rect
			(at 2.800096 0.32512 270)
			(size 0.3048 1.6002)
			(layers "F.Cu" "F.Mask" "F.Paste")
			(net "Net_8620")
		)
		(pad "19" smd rect
			(at 2.800096 -0.32512 270)
			(size 0.3048 1.6002)
			(layers "F.Cu" "F.Mask" "F.Paste")
			(net "Net_8616")
		)
		(pad "20" smd rect
			(at 2.800096 -0.975106 270)
			(size 0.3048 1.6002)
			(layers "F.Cu" "F.Mask" "F.Paste")
			(net "Net_8619")
		)
		(pad "21" smd rect
			(at 2.800096 -1.625092 270)
			(size 0.3048 1.6002)
			(layers "F.Cu" "F.Mask" "F.Paste")
			(net "PCA9548_PCIE0_ADDR2")
		)
		(pad "22" smd rect
			(at 2.800096 -2.275078 270)
			(size 0.3048 1.6002)
			(layers "F.Cu" "F.Mask" "F.Paste")
			(net "SMB_VR_SENSOR_3V3AUX_SCL_R")
		)
		(pad "23" smd rect
			(at 2.800096 -2.925064 270)
			(size 0.3048 1.6002)
			(layers "F.Cu" "F.Mask" "F.Paste")
			(net "SMB_VR_SENSOR_3V3AUX_SDA_R")
		)
		(pad "24" smd rect
			(at 2.800096 -3.57505 270)
			(size 0.3048 1.6002)
			(layers "F.Cu" "F.Mask" "F.Paste")
			(net "P3V3_AUX")
		)
	)
)
